# BASEBOARD_FAB2 (Tioga Pass) — schematic netlist excerpt (pin names and nets, part order shuffled) for the footprints in the layout excerpt that follows; sources: Cadence DE-HDL packaged netlist, KiCad conversion of Wiwynn_Tioga_Pass_MB.brd

U1E1  TMP421  IC  pkg TSSOP  page 167
  DXP  = ISENSE_TMP421_2_DXP
  DXN  = ISENSE_TMP421_2_DXN
  A(1)  = PD_TMP421_2_A1
  A(0)  = PU_TMP421_2_A0
  GND  = GND
  SDA  = SMB_SENSOR_TMP421_2_SDA
  SCL  = SMB_SENSOR_TMP421_2_SCL
  VP  = P3V3_STBY

R4G8  RES  0.0 5% CHIP  pkg 0402  page 233 : A = PVPP_GHJ ; B = VSENSE_PVPP_GHJ

(kicad_pcb
	(version 20260206)
	(generator "pcbnew")
	(generator_version "10.0")
	(general
		(thickness 1.6)
		(legacy_teardrops no)
	)
	(paper "A4")
	(title_block
		(title "Wiwynn_Tioga_Pass_MB.brd")
		(comment 1 "Tioga Pass / footprints 1881-1882 of 4770")
	)
	(layers
		(0 "F.Cu" signal "TOP")
		(4 "In1.Cu" signal "L2GND")
		(6 "In2.Cu" signal "L3")
		(8 "In3.Cu" signal "L4GND")
		(10 "In4.Cu" signal "L5")
		(12 "In5.Cu" signal "L6GND")
		(14 "In6.Cu" signal "L7VCC")
		(16 "In7.Cu" signal "L8VCC")
		(18 "In8.Cu" signal "L9GND")
		(20 "In9.Cu" signal "L10")
		(22 "In10.Cu" signal "L11GND")
		(24 "In11.Cu" signal "L12")
		(26 "In12.Cu" signal "L13GND")
		(2 "B.Cu" signal "BOTTOM")
		(9 "F.Adhes" user "F.Adhesive")
		(11 "B.Adhes" user "B.Adhesive")
		(13 "F.Paste" user "Package Geometry/Pastemask Top")
		(15 "B.Paste" user "Package Geometry/Pastemask Bottom")
		(5 "F.SilkS" user "Ref Des/Silkscreen Top")
		(7 "B.SilkS" user "Ref Des/Silkscreen Bottom")
		(1 "F.Mask" user "Board Geometry/Soldermask Top")
		(3 "B.Mask" user "Board Geometry/Soldermask Bottom")
		(17 "Dwgs.User" user "User.Drawings")
		(19 "Cmts.User" user "User.Comments")
		(21 "Eco1.User" user "User.Eco1")
		(23 "Eco2.User" user "User.Eco2")
		(25 "Edge.Cuts" user "Board Geometry/Outline")
		(27 "Margin" user)
		(31 "F.CrtYd" user "Package Geometry/Place Bound Top")
		(29 "B.CrtYd" user "Package Geometry/Place Bound Bottom")
		(35 "F.Fab" user "Ref Des/Assembly Top")
		(33 "B.Fab" user "Ref Des/Assembly Bottom")
	)
	(footprint ""
		(layer "F.Cu")
		(at 0.762 -71.247 90)
		(property "Reference" "U1E1"
			(at 2.0066 -2.13233 90)
			(unlocked yes)
			(layer "F.SilkS")
			(effects
				(font
					(size 0.7874 0.5842)
					(thickness 0.1524)
				)
			)
		)
		(property "Value" ""
			(at 0 0 90)
			(layer "F.Fab")
			(effects
				(font
					(size 1.27 1.27)
				)
			)
		)
		(duplicate_pad_numbers_are_jumpers no)
		(fp_line
			(start 1.566672 -0.52324)
			(end 0.985774 -0.52324)
			(stroke
				(width 0.1524)
				(type default)
			)
			(layer "F.SilkS")
		)
		(fp_line
			(start 1.583436 2.47396)
			(end 0.965454 2.47396)
			(stroke
				(width 0.1524)
				(type default)
			)
			(layer "F.SilkS")
		)
		(fp_circle
			(center -0.635 -0.889)
			(end -0.635 -0.762)
			(stroke
				(width 0.254)
				(type default)
			)
			(fill no)
			(layer "F.SilkS")
		)
		(fp_rect
			(start 0.3937 2.47396)
			(end 2.1463 -0.52324)
			(stroke
				(width 0)
				(type default)
			)
			(fill no)
			(layer "F.CrtYd")
		)
		(fp_line
			(start 2.1463 -0.52324)
			(end 2.1463 2.47396)
			(stroke
				(width 0.1)
				(type default)
			)
			(layer "F.Fab")
		)
		(fp_line
			(start 0.3937 -0.52324)
			(end 2.1463 -0.52324)
			(stroke
				(width 0.1)
				(type default)
			)
			(layer "F.Fab")
		)
		(fp_line
			(start 2.1463 2.47396)
			(end 0.3937 2.47396)
			(stroke
				(width 0.1)
				(type default)
			)
			(layer "F.Fab")
		)
		(fp_line
			(start 0.3937 2.47396)
			(end 0.3937 -0.52324)
			(stroke
				(width 0.1)
				(type default)
			)
			(layer "F.Fab")
		)
		(fp_circle
			(center -0.635 -0.889)
			(end -0.635 -0.762)
			(stroke
				(width 0.254)
				(type default)
			)
			(fill no)
			(layer "F.Fab")
		)
		(pad "1" smd rect
			(at 0 0 90)
			(size 1.27 0.381)
			(layers "F.Cu" "F.Mask" "F.Paste")
			(net "ISENSE_TMP421_2_DXP")
		)
		(pad "2" smd rect
			(at 0 0.65024 90)
			(size 1.27 0.381)
			(layers "F.Cu" "F.Mask" "F.Paste")
			(net "ISENSE_TMP421_2_DXN")
		)
		(pad "3" smd rect
			(at 0 1.30048 90)
			(size 1.27 0.381)
			(layers "F.Cu" "F.Mask" "F.Paste")
			(net "PD_TMP421_2_A1")
		)
		(pad "4" smd rect
			(at 0 1.95072 90)
			(size 1.27 0.381)
			(layers "F.Cu" "F.Mask" "F.Paste")
			(net "PU_TMP421_2_A0")
		)
		(pad "5" smd rect
			(at 2.54 1.95072 90)
			(size 1.27 0.381)
			(layers "F.Cu" "F.Mask" "F.Paste")
			(net "GND")
		)
		(pad "6" smd rect
			(at 2.54 1.30048 90)
			(size 1.27 0.381)
			(layers "F.Cu" "F.Mask" "F.Paste")
			(net "SMB_SENSOR_TMP421_2_SDA")
		)
		(pad "7" smd rect
			(at 2.54 0.65024 90)
			(size 1.27 0.381)
			(layers "F.Cu" "F.Mask" "F.Paste")
			(net "SMB_SENSOR_TMP421_2_SCL")
		)
		(pad "8" smd rect
			(at 2.54 0 90)
			(size 1.27 0.381)
			(layers "F.Cu" "F.Mask" "F.Paste")
			(net "P3V3_STBY")
		)
	)
	(footprint ""
		(layer "F.Cu")
		(at 166.977822 -9.013952 90)
		(property "Reference" "R4G8"
			(at 0 0 90)
			(layer "F.SilkS")
			(hide yes)
			(effects
				(font
					(size 1.27 1.27)
				)
			)
		)
		(property "Value" ""
			(at 0 0 90)
			(layer "F.Fab")
			(effects
				(font
					(size 1.27 1.27)
				)
			)
		)
		(duplicate_pad_numbers_are_jumpers no)
		(fp_rect
			(start 0.2794 0.9906)
			(end -0.2794 -0.1016)
			(stroke
				(width 0)
				(type default)
			)
			(fill no)
			(layer "F.CrtYd")
		)
		(fp_line
			(start 0.2794 -0.1016)
			(end -0.2794 -0.1016)
			(stroke
				(width 0.1)
				(type default)
			)
			(layer "F.Fab")
		)
		(fp_line
			(start -0.2794 -0.1016)
			(end -0.2794 0.9906)
			(stroke
				(width 0.1)
				(type default)
			)
			(layer "F.Fab")
		)
		(fp_line
			(start 0.2794 0.9906)
			(end 0.2794 -0.1016)
			(stroke
				(width 0.1)
				(type default)
			)
			(layer "F.Fab")
		)
		(fp_line
			(start -0.2794 0.9906)
			(end 0.2794 0.9906)
			(stroke
				(width 0.1)
				(type default)
			)
			(layer "F.Fab")
		)
		(pad "1" smd rect
			(at 0 0 90)
			(size 0.508 0.508)
			(layers "F.Cu" "F.Mask" "F.Paste")
			(net "PVPP_GHJ")
		)
		(pad "2" smd rect
			(at 0 0.889 90)
			(size 0.508 0.508)
			(layers "F.Cu" "F.Mask" "F.Paste")
			(net "VSENSE_PVPP_GHJ")
		)
		(zone
			(layer "F.Cu")
			(hatch none 0.5)
			(connect_pads
				(clearance 0)
			)
			(min_thickness 0.25)
			(keepout
				(tracks allowed)
				(vias not_allowed)
				(pads allowed)
				(copperpour not_allowed)
				(footprints allowed)
			)
			(placement
				(enabled no)
				(sheetname "")
			)
			(fill
				(thermal_gap 0.5)
				(thermal_bridge_width 0.5)
				(island_removal_mode 0)
			)
			(polygon
				(pts
					(xy 167.612822 -9.267952) (xy 167.231822 -9.267952) (xy 167.231822 -8.759952) (xy 167.612822 -8.759952)
				)
			)
		)
		(zone
			(layer "F.Cu")
			(hatch none 0.5)
			(connect_pads
				(clearance 0)
			)
			(min_thickness 0.25)
			(keepout
				(tracks not_allowed)
				(vias allowed)
				(pads allowed)
				(copperpour not_allowed)
				(footprints allowed)
			)
			(placement
				(enabled no)
				(sheetname "")
			)
			(fill
				(thermal_gap 0.5)
				(thermal_bridge_width 0.5)
				(island_removal_mode 0)
			)
			(polygon
				(pts
					(xy 167.612822 -9.267952) (xy 167.231822 -9.267952) (xy 167.231822 -8.759952) (xy 167.612822 -8.759952)
				)
			)
		)
	)
)
